#ISCELL
  mstr_misc prelim *
  *
#ISCELL
  mstr_symbols design_note *
  *
#ISCELL
  mstr_symbols intel_corp_bpage *
  *
#ISCELL
  mstr_standard offpage *
  page22_i185
#ISCELL
  mstr_standard offpage *
  page22_i186
#CELL
  mstr_discrete res *
  page22_i188
#ISCELL
  mstr_symbols gnd *
  page22_i189
#CELL
  mstr_discrete res *
  page22_i190
#ISCELL
  mstr_standard offpage *
  page22_i195
#ISCELL
  mstr_standard offpage *
  page22_i196
#ISCELL
  mstr_standard offpage *
  page22_i197
#ISCELL
  mstr_standard offpage *
  page22_i198
#ISCELL
  mstr_standard offpage *
  page22_i199
#ISCELL
  mstr_standard offpage *
  page22_i200
#ISCELL
  mstr_symbols vcc_core *
  page22_i202
#ISCELL
  mstr_symbols vcc_core *
  page22_i203
#CELL
  chpset_lib skx_ext_b *
  page22_i204
#ISCELL
  mstr_standard offpage *
  page22_i205
#ISCELL
  mstr_standard offpage *
  page22_i206
#ISCELL
  mstr_standard offpage *
  page22_i207
